(kicad_pcb
	(version 20260206)
	(generator "pcbnew")
	(generator_version "10.0")
	(general
		(thickness 1.6)
		(legacy_teardrops no)
	)
	(paper "A4")
	(title_block
		(title "03242023_DA0F0TMBIJ0_F0T_Motherboard_J_brd_V01_OCP.brd")
		(comment 1 "Grand Teton / footprints 2454-2459 of 6105")
	)
	(layers
		(0 "F.Cu" signal "TOP")
		(4 "In1.Cu" signal "GND")
		(6 "In2.Cu" signal "IN1")
		(8 "In3.Cu" signal "GND1")
		(10 "In4.Cu" signal "IN2")
		(12 "In5.Cu" signal "GND2")
		(14 "In6.Cu" signal "IN3")
		(16 "In7.Cu" signal "GND3")
		(18 "In8.Cu" signal "VCC")
		(20 "In9.Cu" signal "VCC1")
		(22 "In10.Cu" signal "GND4")
		(24 "In11.Cu" signal "IN4")
		(26 "In12.Cu" signal "GND5")
		(28 "In13.Cu" signal "IN5")
		(30 "In14.Cu" signal "GND6")
		(32 "In15.Cu" signal "IN6")
		(34 "In16.Cu" signal "GND7")
		(2 "B.Cu" signal "BOTTOM")
		(9 "F.Adhes" user "F.Adhesive")
		(11 "B.Adhes" user "B.Adhesive")
		(13 "F.Paste" user "Package Geometry/Pastemask Top")
		(15 "B.Paste" user "Package Geometry/Pastemask Bottom")
		(5 "F.SilkS" user "Ref Des/Silkscreen Top")
		(7 "B.SilkS" user "Ref Des/Silkscreen Bottom")
		(1 "F.Mask" user "Board Geometry/Soldermask Top")
		(3 "B.Mask" user "Board Geometry/Soldermask Bottom")
		(17 "Dwgs.User" user "User.Drawings")
		(19 "Cmts.User" user "User.Comments")
		(21 "Eco1.User" user "User.Eco1")
		(23 "Eco2.User" user "User.Eco2")
		(25 "Edge.Cuts" user "Board Geometry/Outline")
		(27 "Margin" user)
		(31 "F.CrtYd" user "Package Geometry/Place Bound Top")
		(29 "B.CrtYd" user "Package Geometry/Place Bound Bottom")
		(35 "F.Fab" user "Ref Des/Assembly Top")
		(33 "B.Fab" user "Ref Des/Assembly Bottom")
	)
	(footprint ""
		(layer "F.Cu")
		(at 62.559438 -31.887922 90)
		(property "Reference" "R3873"
			(at 0 0 90)
			(layer "F.SilkS")
			(hide yes)
			(effects
				(font
					(size 1.27 1.27)
				)
			)
		)
		(property "Value" ""
			(at 0 0 90)
			(layer "F.Fab")
			(effects
				(font
					(size 1.27 1.27)
				)
			)
		)
		(duplicate_pad_numbers_are_jumpers no)
		(fp_line
			(start 0.7874 -0.4064)
			(end 0.7874 0.4064)
			(stroke
				(width 0.1524)
				(type default)
			)
			(layer "F.SilkS")
		)
		(fp_line
			(start -0.7874 -0.4064)
			(end 0.7874 -0.4064)
			(stroke
				(width 0.1524)
				(type default)
			)
			(layer "F.SilkS")
		)
		(fp_line
			(start 0.7874 0.4064)
			(end -0.7874 0.4064)
			(stroke
				(width 0.1524)
				(type default)
			)
			(layer "F.SilkS")
		)
		(fp_line
			(start -0.7874 0.4064)
			(end -0.7874 -0.4064)
			(stroke
				(width 0.1524)
				(type default)
			)
			(layer "F.SilkS")
		)
		(fp_line
			(start -0.12065 -0.305054)
			(end -0.12065 -0.2794)
			(stroke
				(width 0.1)
				(type default)
			)
			(layer "F.Fab")
		)
		(fp_line
			(start -0.67945 -0.305054)
			(end -0.12065 -0.305054)
			(stroke
				(width 0.1)
				(type default)
			)
			(layer "F.Fab")
		)
		(fp_line
			(start 0.67945 -0.3048)
			(end 0.67945 0.3048)
			(stroke
				(width 0.1)
				(type default)
			)
			(layer "F.Fab")
		)
		(fp_line
			(start 0.12065 -0.3048)
			(end 0.67945 -0.3048)
			(stroke
				(width 0.1)
				(type default)
			)
			(layer "F.Fab")
		)
		(fp_line
			(start 0.12065 -0.2794)
			(end 0.12065 -0.3048)
			(stroke
				(width 0.1)
				(type default)
			)
			(layer "F.Fab")
		)
		(fp_line
			(start -0.12065 -0.2794)
			(end 0.12065 -0.2794)
			(stroke
				(width 0.1)
				(type default)
			)
			(layer "F.Fab")
		)
		(fp_line
			(start 0.120396 0.2794)
			(end -0.12065 0.2794)
			(stroke
				(width 0.1)
				(type default)
			)
			(layer "F.Fab")
		)
		(fp_line
			(start -0.12065 0.2794)
			(end -0.12065 0.3048)
			(stroke
				(width 0.1)
				(type default)
			)
			(layer "F.Fab")
		)
		(fp_line
			(start 0.67945 0.3048)
			(end 0.120396 0.3048)
			(stroke
				(width 0.1)
				(type default)
			)
			(layer "F.Fab")
		)
		(fp_line
			(start 0.120396 0.3048)
			(end 0.120396 0.2794)
			(stroke
				(width 0.1)
				(type default)
			)
			(layer "F.Fab")
		)
		(fp_line
			(start -0.12065 0.3048)
			(end -0.67945 0.3048)
			(stroke
				(width 0.1)
				(type default)
			)
			(layer "F.Fab")
		)
		(fp_line
			(start -0.67945 0.3048)
			(end -0.67945 -0.305054)
			(stroke
				(width 0.1)
				(type default)
			)
			(layer "F.Fab")
		)
		(pad "1" smd circle
			(at -0.40005 0 90)
			(size 0 0)
			(layers "F.Cu" "F.Mask" "F.Paste")
			(net "P12V_OCP_IMON_2")
		)
		(pad "2" smd circle
			(at 0.40005 0 90)
			(size 0 0)
			(layers "F.Cu" "F.Mask" "F.Paste")
			(net "P12V_OCP_V3_2_ISENSE_MPS_MAM")
		)
	)
	(footprint ""
		(layer "F.Cu")
		(at 157.02788 -118.836948 180)
		(property "Reference" "R982"
			(at 0 0 180)
			(layer "F.SilkS")
			(hide yes)
			(effects
				(font
					(size 1.27 1.27)
				)
			)
		)
		(property "Value" ""
			(at 0 0 180)
			(layer "F.Fab")
			(effects
				(font
					(size 1.27 1.27)
				)
			)
		)
		(duplicate_pad_numbers_are_jumpers no)
		(fp_line
			(start 0.7874 0.4064)
			(end -0.7874 0.4064)
			(stroke
				(width 0.1524)
				(type default)
			)
			(layer "F.SilkS")
		)
		(fp_line
			(start 0.7874 -0.4064)
			(end 0.7874 0.4064)
			(stroke
				(width 0.1524)
				(type default)
			)
			(layer "F.SilkS")
		)
		(fp_line
			(start -0.7874 0.4064)
			(end -0.7874 -0.4064)
			(stroke
				(width 0.1524)
				(type default)
			)
			(layer "F.SilkS")
		)
		(fp_line
			(start -0.7874 -0.4064)
			(end 0.7874 -0.4064)
			(stroke
				(width 0.1524)
				(type default)
			)
			(layer "F.SilkS")
		)
		(fp_line
			(start 0.67945 0.3048)
			(end 0.120396 0.3048)
			(stroke
				(width 0.1)
				(type default)
			)
			(layer "F.Fab")
		)
		(fp_line
			(start 0.67945 -0.3048)
			(end 0.67945 0.3048)
			(stroke
				(width 0.1)
				(type default)
			)
			(layer "F.Fab")
		)
		(fp_line
			(start 0.12065 -0.2794)
			(end 0.12065 -0.3048)
			(stroke
				(width 0.1)
				(type default)
			)
			(layer "F.Fab")
		)
		(fp_line
			(start 0.12065 -0.3048)
			(end 0.67945 -0.3048)
			(stroke
				(width 0.1)
				(type default)
			)
			(layer "F.Fab")
		)
		(fp_line
			(start 0.120396 0.3048)
			(end 0.120396 0.2794)
			(stroke
				(width 0.1)
				(type default)
			)
			(layer "F.Fab")
		)
		(fp_line
			(start 0.120396 0.2794)
			(end -0.12065 0.2794)
			(stroke
				(width 0.1)
				(type default)
			)
			(layer "F.Fab")
		)
		(fp_line
			(start -0.12065 0.3048)
			(end -0.67945 0.3048)
			(stroke
				(width 0.1)
				(type default)
			)
			(layer "F.Fab")
		)
		(fp_line
			(start -0.12065 0.2794)
			(end -0.12065 0.3048)
			(stroke
				(width 0.1)
				(type default)
			)
			(layer "F.Fab")
		)
		(fp_line
			(start -0.12065 -0.2794)
			(end 0.12065 -0.2794)
			(stroke
				(width 0.1)
				(type default)
			)
			(layer "F.Fab")
		)
		(fp_line
			(start -0.12065 -0.305054)
			(end -0.12065 -0.2794)
			(stroke
				(width 0.1)
				(type default)
			)
			(layer "F.Fab")
		)
		(fp_line
			(start -0.67945 0.3048)
			(end -0.67945 -0.305054)
			(stroke
				(width 0.1)
				(type default)
			)
			(layer "F.Fab")
		)
		(fp_line
			(start -0.67945 -0.305054)
			(end -0.12065 -0.305054)
			(stroke
				(width 0.1)
				(type default)
			)
			(layer "F.Fab")
		)
		(pad "1" smd circle
			(at -0.40005 0 180)
			(size 0 0)
			(layers "F.Cu" "F.Mask" "F.Paste")
			(net "FM_PVCCFA_EHV_CPU0_R_EN")
		)
		(pad "2" smd circle
			(at 0.40005 0 180)
			(size 0 0)
			(layers "F.Cu" "F.Mask" "F.Paste")
			(net "FM_PVCCFA_EHV_CPU0_EN")
		)
	)
	(footprint ""
		(layer "F.Cu")
		(at 389.312658 -343.018872 -90)
		(property "Reference" "PC232_P0_8"
			(at 0 0 270)
			(layer "F.SilkS")
			(hide yes)
			(effects
				(font
					(size 1.27 1.27)
				)
			)
		)
		(property "Value" ""
			(at 0 0 270)
			(layer "F.Fab")
			(effects
				(font
					(size 1.27 1.27)
				)
			)
		)
		(duplicate_pad_numbers_are_jumpers no)
		(fp_line
			(start -0.7874 0.4064)
			(end -0.7874 -0.4064)
			(stroke
				(width 0.1524)
				(type default)
			)
			(layer "F.SilkS")
		)
		(fp_line
			(start 0.7874 0.4064)
			(end -0.7874 0.4064)
			(stroke
				(width 0.1524)
				(type default)
			)
			(layer "F.SilkS")
		)
		(fp_line
			(start -0.7874 -0.4064)
			(end 0.7874 -0.4064)
			(stroke
				(width 0.1524)
				(type default)
			)
			(layer "F.SilkS")
		)
		(fp_line
			(start 0.7874 -0.4064)
			(end 0.7874 0.4064)
			(stroke
				(width 0.1524)
				(type default)
			)
			(layer "F.SilkS")
		)
		(fp_line
			(start -0.67945 0.3048)
			(end -0.67945 -0.305054)
			(stroke
				(width 0.1)
				(type default)
			)
			(layer "F.Fab")
		)
		(fp_line
			(start -0.12065 0.3048)
			(end -0.67945 0.3048)
			(stroke
				(width 0.1)
				(type default)
			)
			(layer "F.Fab")
		)
		(fp_line
			(start 0.120396 0.3048)
			(end 0.120396 0.2794)
			(stroke
				(width 0.1)
				(type default)
			)
			(layer "F.Fab")
		)
		(fp_line
			(start 0.67945 0.3048)
			(end 0.120396 0.3048)
			(stroke
				(width 0.1)
				(type default)
			)
			(layer "F.Fab")
		)
		(fp_line
			(start -0.12065 0.2794)
			(end -0.12065 0.3048)
			(stroke
				(width 0.1)
				(type default)
			)
			(layer "F.Fab")
		)
		(fp_line
			(start 0.120396 0.2794)
			(end -0.12065 0.2794)
			(stroke
				(width 0.1)
				(type default)
			)
			(layer "F.Fab")
		)
		(fp_line
			(start -0.12065 -0.2794)
			(end 0.12065 -0.2794)
			(stroke
				(width 0.1)
				(type default)
			)
			(layer "F.Fab")
		)
		(fp_line
			(start 0.12065 -0.2794)
			(end 0.12065 -0.3048)
			(stroke
				(width 0.1)
				(type default)
			)
			(layer "F.Fab")
		)
		(fp_line
			(start 0.12065 -0.3048)
			(end 0.67945 -0.3048)
			(stroke
				(width 0.1)
				(type default)
			)
			(layer "F.Fab")
		)
		(fp_line
			(start 0.67945 -0.3048)
			(end 0.67945 0.3048)
			(stroke
				(width 0.1)
				(type default)
			)
			(layer "F.Fab")
		)
		(fp_line
			(start -0.67945 -0.305054)
			(end -0.12065 -0.305054)
			(stroke
				(width 0.1)
				(type default)
			)
			(layer "F.Fab")
		)
		(fp_line
			(start -0.12065 -0.305054)
			(end -0.12065 -0.2794)
			(stroke
				(width 0.1)
				(type default)
			)
			(layer "F.Fab")
		)
		(pad "1" smd circle
			(at -0.40005 0 270)
			(size 0 0)
			(layers "F.Cu" "F.Mask" "F.Paste")
			(net "SW_P12V_PVCCIN_CPU0_FLT")
		)
		(pad "2" smd circle
			(at 0.40005 0 270)
			(size 0 0)
			(layers "F.Cu" "F.Mask" "F.Paste")
			(net "GND")
		)
	)
	(footprint ""
		(layer "F.Cu")
		(at 80.550766 -65.082674 -90)
		(property "Reference" "R1371"
			(at 0 0 270)
			(layer "F.SilkS")
			(hide yes)
			(effects
				(font
					(size 1.27 1.27)
				)
			)
		)
		(property "Value" ""
			(at 0 0 270)
			(layer "F.Fab")
			(effects
				(font
					(size 1.27 1.27)
				)
			)
		)
		(duplicate_pad_numbers_are_jumpers no)
		(fp_line
			(start -0.7874 0.4064)
			(end -0.7874 -0.4064)
			(stroke
				(width 0.1524)
				(type default)
			)
			(layer "F.SilkS")
		)
		(fp_line
			(start 0.7874 0.4064)
			(end -0.7874 0.4064)
			(stroke
				(width 0.1524)
				(type default)
			)
			(layer "F.SilkS")
		)
		(fp_line
			(start -0.7874 -0.4064)
			(end 0.7874 -0.4064)
			(stroke
				(width 0.1524)
				(type default)
			)
			(layer "F.SilkS")
		)
		(fp_line
			(start 0.7874 -0.4064)
			(end 0.7874 0.4064)
			(stroke
				(width 0.1524)
				(type default)
			)
			(layer "F.SilkS")
		)
		(fp_line
			(start -0.67945 0.3048)
			(end -0.67945 -0.305054)
			(stroke
				(width 0.1)
				(type default)
			)
			(layer "F.Fab")
		)
		(fp_line
			(start -0.12065 0.3048)
			(end -0.67945 0.3048)
			(stroke
				(width 0.1)
				(type default)
			)
			(layer "F.Fab")
		)
		(fp_line
			(start 0.120396 0.3048)
			(end 0.120396 0.2794)
			(stroke
				(width 0.1)
				(type default)
			)
			(layer "F.Fab")
		)
		(fp_line
			(start 0.67945 0.3048)
			(end 0.120396 0.3048)
			(stroke
				(width 0.1)
				(type default)
			)
			(layer "F.Fab")
		)
		(fp_line
			(start -0.12065 0.2794)
			(end -0.12065 0.3048)
			(stroke
				(width 0.1)
				(type default)
			)
			(layer "F.Fab")
		)
		(fp_line
			(start 0.120396 0.2794)
			(end -0.12065 0.2794)
			(stroke
				(width 0.1)
				(type default)
			)
			(layer "F.Fab")
		)
		(fp_line
			(start -0.12065 -0.2794)
			(end 0.12065 -0.2794)
			(stroke
				(width 0.1)
				(type default)
			)
			(layer "F.Fab")
		)
		(fp_line
			(start 0.12065 -0.2794)
			(end 0.12065 -0.3048)
			(stroke
				(width 0.1)
				(type default)
			)
			(layer "F.Fab")
		)
		(fp_line
			(start 0.12065 -0.3048)
			(end 0.67945 -0.3048)
			(stroke
				(width 0.1)
				(type default)
			)
			(layer "F.Fab")
		)
		(fp_line
			(start 0.67945 -0.3048)
			(end 0.67945 0.3048)
			(stroke
				(width 0.1)
				(type default)
			)
			(layer "F.Fab")
		)
		(fp_line
			(start -0.67945 -0.305054)
			(end -0.12065 -0.305054)
			(stroke
				(width 0.1)
				(type default)
			)
			(layer "F.Fab")
		)
		(fp_line
			(start -0.12065 -0.305054)
			(end -0.12065 -0.2794)
			(stroke
				(width 0.1)
				(type default)
			)
			(layer "F.Fab")
		)
		(pad "1" smd circle
			(at -0.40005 0 270)
			(size 0 0)
			(layers "F.Cu" "F.Mask" "F.Paste")
			(net "LED_RST_PLD_CPU0_DRAM_AB_N")
		)
		(pad "2" smd circle
			(at 0.40005 0 270)
			(size 0 0)
			(layers "F.Cu" "F.Mask" "F.Paste")
			(net "P3V3_AUX")
		)
	)
	(footprint ""
		(layer "F.Cu")
		(at 106.331004 -245.634256 -90)
		(property "Reference" "C276"
			(at 0 0 270)
			(layer "F.SilkS")
			(hide yes)
			(effects
				(font
					(size 1.27 1.27)
				)
			)
		)
		(property "Value" ""
			(at 0 0 270)
			(layer "F.Fab")
			(effects
				(font
					(size 1.27 1.27)
				)
			)
		)
		(duplicate_pad_numbers_are_jumpers no)
		(fp_line
			(start -0.7874 0.4064)
			(end -0.7874 -0.4064)
			(stroke
				(width 0.1524)
				(type default)
			)
			(layer "F.SilkS")
		)
		(fp_line
			(start 0.7874 0.4064)
			(end -0.7874 0.4064)
			(stroke
				(width 0.1524)
				(type default)
			)
			(layer "F.SilkS")
		)
		(fp_line
			(start -0.7874 -0.4064)
			(end 0.7874 -0.4064)
			(stroke
				(width 0.1524)
				(type default)
			)
			(layer "F.SilkS")
		)
		(fp_line
			(start 0.7874 -0.4064)
			(end 0.7874 0.4064)
			(stroke
				(width 0.1524)
				(type default)
			)
			(layer "F.SilkS")
		)
		(fp_line
			(start -0.67945 0.3048)
			(end -0.67945 -0.305054)
			(stroke
				(width 0.1)
				(type default)
			)
			(layer "F.Fab")
		)
		(fp_line
			(start -0.12065 0.3048)
			(end -0.67945 0.3048)
			(stroke
				(width 0.1)
				(type default)
			)
			(layer "F.Fab")
		)
		(fp_line
			(start 0.120396 0.3048)
			(end 0.120396 0.2794)
			(stroke
				(width 0.1)
				(type default)
			)
			(layer "F.Fab")
		)
		(fp_line
			(start 0.67945 0.3048)
			(end 0.120396 0.3048)
			(stroke
				(width 0.1)
				(type default)
			)
			(layer "F.Fab")
		)
		(fp_line
			(start -0.12065 0.2794)
			(end -0.12065 0.3048)
			(stroke
				(width 0.1)
				(type default)
			)
			(layer "F.Fab")
		)
		(fp_line
			(start 0.120396 0.2794)
			(end -0.12065 0.2794)
			(stroke
				(width 0.1)
				(type default)
			)
			(layer "F.Fab")
		)
		(fp_line
			(start -0.12065 -0.2794)
			(end 0.12065 -0.2794)
			(stroke
				(width 0.1)
				(type default)
			)
			(layer "F.Fab")
		)
		(fp_line
			(start 0.12065 -0.2794)
			(end 0.12065 -0.3048)
			(stroke
				(width 0.1)
				(type default)
			)
			(layer "F.Fab")
		)
		(fp_line
			(start 0.12065 -0.3048)
			(end 0.67945 -0.3048)
			(stroke
				(width 0.1)
				(type default)
			)
			(layer "F.Fab")
		)
		(fp_line
			(start 0.67945 -0.3048)
			(end 0.67945 0.3048)
			(stroke
				(width 0.1)
				(type default)
			)
			(layer "F.Fab")
		)
		(fp_line
			(start -0.67945 -0.305054)
			(end -0.12065 -0.305054)
			(stroke
				(width 0.1)
				(type default)
			)
			(layer "F.Fab")
		)
		(fp_line
			(start -0.12065 -0.305054)
			(end -0.12065 -0.2794)
			(stroke
				(width 0.1)
				(type default)
			)
			(layer "F.Fab")
		)
		(pad "1" smd circle
			(at -0.40005 0 270)
			(size 0 0)
			(layers "F.Cu" "F.Mask" "F.Paste")
			(net "PVCCIN_CPU1")
		)
		(pad "2" smd circle
			(at 0.40005 0 270)
			(size 0 0)
			(layers "F.Cu" "F.Mask" "F.Paste")
			(net "GND")
		)
	)
	(footprint ""
		(layer "F.Cu")
		(at 312.443622 -43.932348)
		(property "Reference" "R1259"
			(at 0 0 0)
			(layer "F.SilkS")
			(hide yes)
			(effects
				(font
					(size 1.27 1.27)
				)
			)
		)
		(property "Value" ""
			(at 0 0 0)
			(layer "F.Fab")
			(effects
				(font
					(size 1.27 1.27)
				)
			)
		)
		(duplicate_pad_numbers_are_jumpers no)
		(fp_line
			(start -0.7874 -0.4064)
			(end 0.7874 -0.4064)
			(stroke
				(width 0.1524)
				(type default)
			)
			(layer "F.SilkS")
		)
		(fp_line
			(start -0.7874 0.4064)
			(end -0.7874 -0.4064)
			(stroke
				(width 0.1524)
				(type default)
			)
			(layer "F.SilkS")
		)
		(fp_line
			(start 0.7874 -0.4064)
			(end 0.7874 0.4064)
			(stroke
				(width 0.1524)
				(type default)
			)
			(layer "F.SilkS")
		)
		(fp_line
			(start 0.7874 0.4064)
			(end -0.7874 0.4064)
			(stroke
				(width 0.1524)
				(type default)
			)
			(layer "F.SilkS")
		)
		(fp_line
			(start -0.67945 -0.305054)
			(end -0.12065 -0.305054)
			(stroke
				(width 0.1)
				(type default)
			)
			(layer "F.Fab")
		)
		(fp_line
			(start -0.67945 0.3048)
			(end -0.67945 -0.305054)
			(stroke
				(width 0.1)
				(type default)
			)
			(layer "F.Fab")
		)
		(fp_line
			(start -0.12065 -0.305054)
			(end -0.12065 -0.2794)
			(stroke
				(width 0.1)
				(type default)
			)
			(layer "F.Fab")
		)
		(fp_line
			(start -0.12065 -0.2794)
			(end 0.12065 -0.2794)
			(stroke
				(width 0.1)
				(type default)
			)
			(layer "F.Fab")
		)
		(fp_line
			(start -0.12065 0.2794)
			(end -0.12065 0.3048)
			(stroke
				(width 0.1)
				(type default)
			)
			(layer "F.Fab")
		)
		(fp_line
			(start -0.12065 0.3048)
			(end -0.67945 0.3048)
			(stroke
				(width 0.1)
				(type default)
			)
			(layer "F.Fab")
		)
		(fp_line
			(start 0.120396 0.2794)
			(end -0.12065 0.2794)
			(stroke
				(width 0.1)
				(type default)
			)
			(layer "F.Fab")
		)
		(fp_line
			(start 0.120396 0.3048)
			(end 0.120396 0.2794)
			(stroke
				(width 0.1)
				(type default)
			)
			(layer "F.Fab")
		)
		(fp_line
			(start 0.12065 -0.3048)
			(end 0.67945 -0.3048)
			(stroke
				(width 0.1)
				(type default)
			)
			(layer "F.Fab")
		)
		(fp_line
			(start 0.12065 -0.2794)
			(end 0.12065 -0.3048)
			(stroke
				(width 0.1)
				(type default)
			)
			(layer "F.Fab")
		)
		(fp_line
			(start 0.67945 -0.3048)
			(end 0.67945 0.3048)
			(stroke
				(width 0.1)
				(type default)
			)
			(layer "F.Fab")
		)
		(fp_line
			(start 0.67945 0.3048)
			(end 0.120396 0.3048)
			(stroke
				(width 0.1)
				(type default)
			)
			(layer "F.Fab")
		)
		(pad "1" smd circle
			(at -0.40005 0)
			(size 0 0)
			(layers "F.Cu" "F.Mask" "F.Paste")
			(net "P3V3_AUX")
		)
		(pad "2" smd circle
			(at 0.40005 0)
			(size 0 0)
			(layers "F.Cu" "F.Mask" "F.Paste")
			(net "PU_LPC_PME_N")
		)
	)
)
